# T6G (Grand Teton) — schematic netlist excerpt (pin names and nets, part order shuffled) for the footprints in the layout excerpt that follows; sources: Cadence DE-HDL packaged netlist, KiCad conversion of 04192023_DAF0TMB3IC0_F0TG_MB_C_brd_V02_OCP.brd

PR186  Q_RES  2.2 1% CHIP  pkg 0402LF  page 211 : A = PVDDCR_CPU0_P1_PVCC ; B = PVDDCR_CPU0_P1_VCC2
C470  Q_CAP  1UF 4V 20% X6S  pkg 0201  page 356 : A = P0V9_CPU1_RT3_2A ; B = GND
PR6808  Q_RES  0 5% EMPTY  pkg 0402LF  page 364 : A = P12V_AUX ; B = P0V9_RETIMER_CPU1_VMON

(kicad_pcb
	(version 20260206)
	(generator "pcbnew")
	(generator_version "10.0")
	(general
		(thickness 1.6)
		(legacy_teardrops no)
	)
	(paper "A4")
	(title_block
		(title "04192023_DAF0TMB3IC0_F0TG_MB_C_brd_V02_OCP.brd")
		(comment 1 "Grand Teton / footprints 5686-5688 of 8354")
	)
	(layers
		(0 "F.Cu" signal "TOP")
		(4 "In1.Cu" signal "GND")
		(6 "In2.Cu" signal "IN1")
		(8 "In3.Cu" signal "GND1")
		(10 "In4.Cu" signal "IN2")
		(12 "In5.Cu" signal "GND2")
		(14 "In6.Cu" signal "IN3")
		(16 "In7.Cu" signal "GND3")
		(18 "In8.Cu" signal "VCC")
		(20 "In9.Cu" signal "VCC1")
		(22 "In10.Cu" signal "GND4")
		(24 "In11.Cu" signal "IN4")
		(26 "In12.Cu" signal "GND5")
		(28 "In13.Cu" signal "IN5")
		(30 "In14.Cu" signal "GND6")
		(32 "In15.Cu" signal "IN6")
		(34 "In16.Cu" signal "GND7")
		(2 "B.Cu" signal "BOTTOM")
		(9 "F.Adhes" user "F.Adhesive")
		(11 "B.Adhes" user "B.Adhesive")
		(13 "F.Paste" user "Package Geometry/Pastemask Top")
		(15 "B.Paste" user "Package Geometry/Pastemask Bottom")
		(5 "F.SilkS" user "Ref Des/Silkscreen Top")
		(7 "B.SilkS" user "Ref Des/Silkscreen Bottom")
		(1 "F.Mask" user "Board Geometry/Soldermask Top")
		(3 "B.Mask" user "Board Geometry/Soldermask Bottom")
		(17 "Dwgs.User" user "User.Drawings")
		(19 "Cmts.User" user "User.Comments")
		(21 "Eco1.User" user "User.Eco1")
		(23 "Eco2.User" user "User.Eco2")
		(25 "Edge.Cuts" user "Board Geometry/Outline")
		(27 "Margin" user)
		(31 "F.CrtYd" user "Package Geometry/Place Bound Top")
		(29 "B.CrtYd" user "Package Geometry/Place Bound Bottom")
		(35 "F.Fab" user "Ref Des/Assembly Top")
		(33 "B.Fab" user "Ref Des/Assembly Bottom")
	)
	(footprint ""
		(layer "B.Cu")
		(at 12.234418 -414.37687 90)
		(property "Reference" "PR6808"
			(at 0 0 90)
			(layer "B.SilkS")
			(hide yes)
			(effects
				(font
					(size 1.27 1.27)
				)
				(justify mirror)
			)
		)
		(property "Value" ""
			(at 0 0 90)
			(layer "B.Fab")
			(effects
				(font
					(size 1.27 1.27)
				)
				(justify mirror)
			)
		)
		(duplicate_pad_numbers_are_jumpers no)
		(fp_line
			(start 0.7874 -0.4064)
			(end -0.7874 -0.4064)
			(stroke
				(width 0.1524)
				(type default)
			)
			(layer "B.SilkS")
		)
		(fp_line
			(start -0.7874 -0.4064)
			(end -0.7874 0.4064)
			(stroke
				(width 0.1524)
				(type default)
			)
			(layer "B.SilkS")
		)
		(fp_line
			(start 0.7874 0.4064)
			(end 0.7874 -0.4064)
			(stroke
				(width 0.1524)
				(type default)
			)
			(layer "B.SilkS")
		)
		(fp_line
			(start -0.7874 0.4064)
			(end 0.7874 0.4064)
			(stroke
				(width 0.1524)
				(type default)
			)
			(layer "B.SilkS")
		)
		(fp_line
			(start 0.67945 -0.305054)
			(end 0.12065 -0.305054)
			(stroke
				(width 0.1)
				(type default)
			)
			(layer "B.Fab")
		)
		(fp_line
			(start 0.12065 -0.305054)
			(end 0.12065 -0.2794)
			(stroke
				(width 0.1)
				(type default)
			)
			(layer "B.Fab")
		)
		(fp_line
			(start -0.12065 -0.3048)
			(end -0.67945 -0.3048)
			(stroke
				(width 0.1)
				(type default)
			)
			(layer "B.Fab")
		)
		(fp_line
			(start -0.67945 -0.3048)
			(end -0.67945 0.3048)
			(stroke
				(width 0.1)
				(type default)
			)
			(layer "B.Fab")
		)
		(fp_line
			(start 0.12065 -0.2794)
			(end -0.12065 -0.2794)
			(stroke
				(width 0.1)
				(type default)
			)
			(layer "B.Fab")
		)
		(fp_line
			(start -0.12065 -0.2794)
			(end -0.12065 -0.3048)
			(stroke
				(width 0.1)
				(type default)
			)
			(layer "B.Fab")
		)
		(fp_line
			(start 0.12065 0.2794)
			(end 0.12065 0.3048)
			(stroke
				(width 0.1)
				(type default)
			)
			(layer "B.Fab")
		)
		(fp_line
			(start -0.120396 0.2794)
			(end 0.12065 0.2794)
			(stroke
				(width 0.1)
				(type default)
			)
			(layer "B.Fab")
		)
		(fp_line
			(start 0.67945 0.3048)
			(end 0.67945 -0.305054)
			(stroke
				(width 0.1)
				(type default)
			)
			(layer "B.Fab")
		)
		(fp_line
			(start 0.12065 0.3048)
			(end 0.67945 0.3048)
			(stroke
				(width 0.1)
				(type default)
			)
			(layer "B.Fab")
		)
		(fp_line
			(start -0.120396 0.3048)
			(end -0.120396 0.2794)
			(stroke
				(width 0.1)
				(type default)
			)
			(layer "B.Fab")
		)
		(fp_line
			(start -0.67945 0.3048)
			(end -0.120396 0.3048)
			(stroke
				(width 0.1)
				(type default)
			)
			(layer "B.Fab")
		)
		(pad "1" smd circle
			(at 0.40005 0 270)
			(size 0 0)
			(layers "B.Cu" "B.Mask" "B.Paste")
			(net "P12V_AUX")
		)
		(pad "2" smd circle
			(at -0.40005 0 270)
			(size 0 0)
			(layers "B.Cu" "B.Mask" "B.Paste")
			(net "P0V9_RETIMER_CPU1_VMON")
		)
	)
	(footprint ""
		(layer "B.Cu")
		(at 131.27863 -386.766562 90)
		(property "Reference" "C470"
			(at 0 0 90)
			(layer "B.SilkS")
			(hide yes)
			(effects
				(font
					(size 1.27 1.27)
				)
				(justify mirror)
			)
		)
		(property "Value" ""
			(at 0 0 90)
			(layer "B.Fab")
			(effects
				(font
					(size 1.27 1.27)
				)
				(justify mirror)
			)
		)
		(duplicate_pad_numbers_are_jumpers no)
		(fp_line
			(start 0.299974 -0.150114)
			(end -0.299974 -0.150114)
			(stroke
				(width 0.1)
				(type default)
			)
			(layer "B.Fab")
		)
		(fp_line
			(start -0.299974 -0.150114)
			(end -0.299974 0.150114)
			(stroke
				(width 0.1)
				(type default)
			)
			(layer "B.Fab")
		)
		(fp_line
			(start 0.299974 0.150114)
			(end 0.299974 -0.150114)
			(stroke
				(width 0.1)
				(type default)
			)
			(layer "B.Fab")
		)
		(fp_line
			(start -0.299974 0.150114)
			(end 0.299974 0.150114)
			(stroke
				(width 0.1)
				(type default)
			)
			(layer "B.Fab")
		)
		(pad "1" smd rect
			(at 0.2667 0 270)
			(size 0.3048 0.381)
			(layers "B.Cu" "B.Mask" "B.Paste")
			(net "P0V9_CPU1_RT3_2A")
		)
		(pad "2" smd rect
			(at -0.2667 0 270)
			(size 0.3048 0.381)
			(layers "B.Cu" "B.Mask" "B.Paste")
			(net "GND")
		)
	)
	(footprint ""
		(layer "B.Cu")
		(at 92.992702 -181.616604 90)
		(property "Reference" "PR186"
			(at 0 0 90)
			(layer "B.SilkS")
			(hide yes)
			(effects
				(font
					(size 1.27 1.27)
				)
				(justify mirror)
			)
		)
		(property "Value" ""
			(at 0 0 90)
			(layer "B.Fab")
			(effects
				(font
					(size 1.27 1.27)
				)
				(justify mirror)
			)
		)
		(duplicate_pad_numbers_are_jumpers no)
		(fp_line
			(start 0.7874 -0.4064)
			(end -0.7874 -0.4064)
			(stroke
				(width 0.1524)
				(type default)
			)
			(layer "B.SilkS")
		)
		(fp_line
			(start -0.7874 -0.4064)
			(end -0.7874 0.4064)
			(stroke
				(width 0.1524)
				(type default)
			)
			(layer "B.SilkS")
		)
		(fp_line
			(start 0.7874 0.4064)
			(end 0.7874 -0.4064)
			(stroke
				(width 0.1524)
				(type default)
			)
			(layer "B.SilkS")
		)
		(fp_line
			(start -0.7874 0.4064)
			(end 0.7874 0.4064)
			(stroke
				(width 0.1524)
				(type default)
			)
			(layer "B.SilkS")
		)
		(fp_line
			(start 0.67945 -0.305054)
			(end 0.12065 -0.305054)
			(stroke
				(width 0.1)
				(type default)
			)
			(layer "B.Fab")
		)
		(fp_line
			(start 0.12065 -0.305054)
			(end 0.12065 -0.2794)
			(stroke
				(width 0.1)
				(type default)
			)
			(layer "B.Fab")
		)
		(fp_line
			(start -0.12065 -0.3048)
			(end -0.67945 -0.3048)
			(stroke
				(width 0.1)
				(type default)
			)
			(layer "B.Fab")
		)
		(fp_line
			(start -0.67945 -0.3048)
			(end -0.67945 0.3048)
			(stroke
				(width 0.1)
				(type default)
			)
			(layer "B.Fab")
		)
		(fp_line
			(start 0.12065 -0.2794)
			(end -0.12065 -0.2794)
			(stroke
				(width 0.1)
				(type default)
			)
			(layer "B.Fab")
		)
		(fp_line
			(start -0.12065 -0.2794)
			(end -0.12065 -0.3048)
			(stroke
				(width 0.1)
				(type default)
			)
			(layer "B.Fab")
		)
		(fp_line
			(start 0.12065 0.2794)
			(end 0.12065 0.3048)
			(stroke
				(width 0.1)
				(type default)
			)
			(layer "B.Fab")
		)
		(fp_line
			(start -0.120396 0.2794)
			(end 0.12065 0.2794)
			(stroke
				(width 0.1)
				(type default)
			)
			(layer "B.Fab")
		)
		(fp_line
			(start 0.67945 0.3048)
			(end 0.67945 -0.305054)
			(stroke
				(width 0.1)
				(type default)
			)
			(layer "B.Fab")
		)
		(fp_line
			(start 0.12065 0.3048)
			(end 0.67945 0.3048)
			(stroke
				(width 0.1)
				(type default)
			)
			(layer "B.Fab")
		)
		(fp_line
			(start -0.120396 0.3048)
			(end -0.120396 0.2794)
			(stroke
				(width 0.1)
				(type default)
			)
			(layer "B.Fab")
		)
		(fp_line
			(start -0.67945 0.3048)
			(end -0.120396 0.3048)
			(stroke
				(width 0.1)
				(type default)
			)
			(layer "B.Fab")
		)
		(pad "1" smd circle
			(at 0.40005 0 270)
			(size 0 0)
			(layers "B.Cu" "B.Mask" "B.Paste")
			(net "PVDDCR_CPU0_P1_PVCC")
		)
		(pad "2" smd circle
			(at -0.40005 0 270)
			(size 0 0)
			(layers "B.Cu" "B.Mask" "B.Paste")
			(net "PVDDCR_CPU0_P1_VCC2")
		)
	)
)
